(kicad_pcb
	(version 20260206)
	(generator "pcbnew")
	(generator_version "10.0")
	(general
		(thickness 1.6)
		(legacy_teardrops no)
	)
	(paper "A4")
	(title_block
		(title "04192023_DAF0TMB3IC0_F0TG_MB_C_brd_V02_OCP.brd")
		(comment 1 "Grand Teton / footprints 6811-6817 of 8354")
	)
	(layers
		(0 "F.Cu" signal "TOP")
		(4 "In1.Cu" signal "GND")
		(6 "In2.Cu" signal "IN1")
		(8 "In3.Cu" signal "GND1")
		(10 "In4.Cu" signal "IN2")
		(12 "In5.Cu" signal "GND2")
		(14 "In6.Cu" signal "IN3")
		(16 "In7.Cu" signal "GND3")
		(18 "In8.Cu" signal "VCC")
		(20 "In9.Cu" signal "VCC1")
		(22 "In10.Cu" signal "GND4")
		(24 "In11.Cu" signal "IN4")
		(26 "In12.Cu" signal "GND5")
		(28 "In13.Cu" signal "IN5")
		(30 "In14.Cu" signal "GND6")
		(32 "In15.Cu" signal "IN6")
		(34 "In16.Cu" signal "GND7")
		(2 "B.Cu" signal "BOTTOM")
		(9 "F.Adhes" user "F.Adhesive")
		(11 "B.Adhes" user "B.Adhesive")
		(13 "F.Paste" user "Package Geometry/Pastemask Top")
		(15 "B.Paste" user "Package Geometry/Pastemask Bottom")
		(5 "F.SilkS" user "Ref Des/Silkscreen Top")
		(7 "B.SilkS" user "Ref Des/Silkscreen Bottom")
		(1 "F.Mask" user "Board Geometry/Soldermask Top")
		(3 "B.Mask" user "Board Geometry/Soldermask Bottom")
		(17 "Dwgs.User" user "User.Drawings")
		(19 "Cmts.User" user "User.Comments")
		(21 "Eco1.User" user "User.Eco1")
		(23 "Eco2.User" user "User.Eco2")
		(25 "Edge.Cuts" user "Board Geometry/Outline")
		(27 "Margin" user)
		(31 "F.CrtYd" user "Package Geometry/Place Bound Top")
		(29 "B.CrtYd" user "Package Geometry/Place Bound Bottom")
		(35 "F.Fab" user "Ref Des/Assembly Top")
		(33 "B.Fab" user "Ref Des/Assembly Bottom")
	)
	(footprint ""
		(layer "B.Cu")
		(at 182.753 -100.294948 90)
		(property "Reference" "R81"
			(at 0 0 90)
			(layer "B.SilkS")
			(hide yes)
			(effects
				(font
					(size 1.27 1.27)
				)
				(justify mirror)
			)
		)
		(property "Value" ""
			(at 0 0 90)
			(layer "B.Fab")
			(effects
				(font
					(size 1.27 1.27)
				)
				(justify mirror)
			)
		)
		(duplicate_pad_numbers_are_jumpers no)
		(fp_line
			(start 0.7874 -0.4064)
			(end -0.7874 -0.4064)
			(stroke
				(width 0.1524)
				(type default)
			)
			(layer "B.SilkS")
		)
		(fp_line
			(start -0.7874 -0.4064)
			(end -0.7874 0.4064)
			(stroke
				(width 0.1524)
				(type default)
			)
			(layer "B.SilkS")
		)
		(fp_line
			(start 0.7874 0.4064)
			(end 0.7874 -0.4064)
			(stroke
				(width 0.1524)
				(type default)
			)
			(layer "B.SilkS")
		)
		(fp_line
			(start -0.7874 0.4064)
			(end 0.7874 0.4064)
			(stroke
				(width 0.1524)
				(type default)
			)
			(layer "B.SilkS")
		)
		(fp_line
			(start 0.67945 -0.305054)
			(end 0.12065 -0.305054)
			(stroke
				(width 0.1)
				(type default)
			)
			(layer "B.Fab")
		)
		(fp_line
			(start 0.12065 -0.305054)
			(end 0.12065 -0.2794)
			(stroke
				(width 0.1)
				(type default)
			)
			(layer "B.Fab")
		)
		(fp_line
			(start -0.12065 -0.3048)
			(end -0.67945 -0.3048)
			(stroke
				(width 0.1)
				(type default)
			)
			(layer "B.Fab")
		)
		(fp_line
			(start -0.67945 -0.3048)
			(end -0.67945 0.3048)
			(stroke
				(width 0.1)
				(type default)
			)
			(layer "B.Fab")
		)
		(fp_line
			(start 0.12065 -0.2794)
			(end -0.12065 -0.2794)
			(stroke
				(width 0.1)
				(type default)
			)
			(layer "B.Fab")
		)
		(fp_line
			(start -0.12065 -0.2794)
			(end -0.12065 -0.3048)
			(stroke
				(width 0.1)
				(type default)
			)
			(layer "B.Fab")
		)
		(fp_line
			(start 0.12065 0.2794)
			(end 0.12065 0.3048)
			(stroke
				(width 0.1)
				(type default)
			)
			(layer "B.Fab")
		)
		(fp_line
			(start -0.120396 0.2794)
			(end 0.12065 0.2794)
			(stroke
				(width 0.1)
				(type default)
			)
			(layer "B.Fab")
		)
		(fp_line
			(start 0.67945 0.3048)
			(end 0.67945 -0.305054)
			(stroke
				(width 0.1)
				(type default)
			)
			(layer "B.Fab")
		)
		(fp_line
			(start 0.12065 0.3048)
			(end 0.67945 0.3048)
			(stroke
				(width 0.1)
				(type default)
			)
			(layer "B.Fab")
		)
		(fp_line
			(start -0.120396 0.3048)
			(end -0.120396 0.2794)
			(stroke
				(width 0.1)
				(type default)
			)
			(layer "B.Fab")
		)
		(fp_line
			(start -0.67945 0.3048)
			(end -0.120396 0.3048)
			(stroke
				(width 0.1)
				(type default)
			)
			(layer "B.Fab")
		)
		(pad "1" smd circle
			(at 0.40005 0 270)
			(size 0 0)
			(layers "B.Cu" "B.Mask" "B.Paste")
			(net "FM_INT_CPU0_HP_UBM_R_N")
		)
		(pad "2" smd circle
			(at -0.40005 0 270)
			(size 0 0)
			(layers "B.Cu" "B.Mask" "B.Paste")
			(net "FM_INT_CPU0_HP_UBM_N")
		)
	)
	(footprint ""
		(layer "B.Cu")
		(at 159.285686 -408.517344 90)
		(property "Reference" "C6754"
			(at 0 0 90)
			(layer "B.SilkS")
			(hide yes)
			(effects
				(font
					(size 1.27 1.27)
				)
				(justify mirror)
			)
		)
		(property "Value" ""
			(at 0 0 90)
			(layer "B.Fab")
			(effects
				(font
					(size 1.27 1.27)
				)
				(justify mirror)
			)
		)
		(duplicate_pad_numbers_are_jumpers no)
		(fp_line
			(start 0.299974 -0.150114)
			(end -0.299974 -0.150114)
			(stroke
				(width 0.1)
				(type default)
			)
			(layer "B.Fab")
		)
		(fp_line
			(start -0.299974 -0.150114)
			(end -0.299974 0.150114)
			(stroke
				(width 0.1)
				(type default)
			)
			(layer "B.Fab")
		)
		(fp_line
			(start 0.299974 0.150114)
			(end 0.299974 -0.150114)
			(stroke
				(width 0.1)
				(type default)
			)
			(layer "B.Fab")
		)
		(fp_line
			(start -0.299974 0.150114)
			(end 0.299974 0.150114)
			(stroke
				(width 0.1)
				(type default)
			)
			(layer "B.Fab")
		)
		(pad "1" smd rect
			(at 0.2667 0 270)
			(size 0.3048 0.381)
			(layers "B.Cu" "B.Mask" "B.Paste")
			(net "P5E_CPU1_P3_TX_BUF_C_DN<14>")
		)
		(pad "2" smd rect
			(at -0.2667 0 270)
			(size 0.3048 0.381)
			(layers "B.Cu" "B.Mask" "B.Paste")
			(net "P5E_CPU1_P3_TX_BUF_DN<14>")
		)
	)
	(footprint ""
		(layer "B.Cu")
		(at 243.713 -326.898 180)
		(property "Reference" "R1227"
			(at 0 0 0)
			(layer "B.SilkS")
			(hide yes)
			(effects
				(font
					(size 1.27 1.27)
				)
				(justify mirror)
			)
		)
		(property "Value" ""
			(at 0 0 0)
			(layer "B.Fab")
			(effects
				(font
					(size 1.27 1.27)
				)
				(justify mirror)
			)
		)
		(duplicate_pad_numbers_are_jumpers no)
		(fp_line
			(start 0.7874 0.4064)
			(end 0.7874 -0.4064)
			(stroke
				(width 0.1524)
				(type default)
			)
			(layer "B.SilkS")
		)
		(fp_line
			(start 0.7874 -0.4064)
			(end -0.7874 -0.4064)
			(stroke
				(width 0.1524)
				(type default)
			)
			(layer "B.SilkS")
		)
		(fp_line
			(start -0.7874 0.4064)
			(end 0.7874 0.4064)
			(stroke
				(width 0.1524)
				(type default)
			)
			(layer "B.SilkS")
		)
		(fp_line
			(start -0.7874 -0.4064)
			(end -0.7874 0.4064)
			(stroke
				(width 0.1524)
				(type default)
			)
			(layer "B.SilkS")
		)
		(fp_line
			(start 0.67945 0.3048)
			(end 0.67945 -0.305054)
			(stroke
				(width 0.1)
				(type default)
			)
			(layer "B.Fab")
		)
		(fp_line
			(start 0.67945 -0.305054)
			(end 0.12065 -0.305054)
			(stroke
				(width 0.1)
				(type default)
			)
			(layer "B.Fab")
		)
		(fp_line
			(start 0.12065 0.3048)
			(end 0.67945 0.3048)
			(stroke
				(width 0.1)
				(type default)
			)
			(layer "B.Fab")
		)
		(fp_line
			(start 0.12065 0.2794)
			(end 0.12065 0.3048)
			(stroke
				(width 0.1)
				(type default)
			)
			(layer "B.Fab")
		)
		(fp_line
			(start 0.12065 -0.2794)
			(end -0.12065 -0.2794)
			(stroke
				(width 0.1)
				(type default)
			)
			(layer "B.Fab")
		)
		(fp_line
			(start 0.12065 -0.305054)
			(end 0.12065 -0.2794)
			(stroke
				(width 0.1)
				(type default)
			)
			(layer "B.Fab")
		)
		(fp_line
			(start -0.120396 0.3048)
			(end -0.120396 0.2794)
			(stroke
				(width 0.1)
				(type default)
			)
			(layer "B.Fab")
		)
		(fp_line
			(start -0.120396 0.2794)
			(end 0.12065 0.2794)
			(stroke
				(width 0.1)
				(type default)
			)
			(layer "B.Fab")
		)
		(fp_line
			(start -0.12065 -0.2794)
			(end -0.12065 -0.3048)
			(stroke
				(width 0.1)
				(type default)
			)
			(layer "B.Fab")
		)
		(fp_line
			(start -0.12065 -0.3048)
			(end -0.67945 -0.3048)
			(stroke
				(width 0.1)
				(type default)
			)
			(layer "B.Fab")
		)
		(fp_line
			(start -0.67945 0.3048)
			(end -0.120396 0.3048)
			(stroke
				(width 0.1)
				(type default)
			)
			(layer "B.Fab")
		)
		(fp_line
			(start -0.67945 -0.3048)
			(end -0.67945 0.3048)
			(stroke
				(width 0.1)
				(type default)
			)
			(layer "B.Fab")
		)
		(pad "1" smd circle
			(at 0.40005 0)
			(size 0 0)
			(layers "B.Cu" "B.Mask" "B.Paste")
			(net "SMB_ADC_SDA_R")
		)
		(pad "2" smd circle
			(at -0.40005 0)
			(size 0 0)
			(layers "B.Cu" "B.Mask" "B.Paste")
			(net "SMB_SEN_MAM_2_3V3AUX_SDA")
		)
	)
	(footprint ""
		(layer "B.Cu")
		(at 365.835692 -257.455162)
		(property "Reference" "C2587"
			(at 0 0 0)
			(layer "B.SilkS")
			(hide yes)
			(effects
				(font
					(size 1.27 1.27)
				)
				(justify mirror)
			)
		)
		(property "Value" ""
			(at 0 0 0)
			(layer "B.Fab")
			(effects
				(font
					(size 1.27 1.27)
				)
				(justify mirror)
			)
		)
		(duplicate_pad_numbers_are_jumpers no)
		(fp_line
			(start -0.7874 -0.4064)
			(end -0.7874 0.4064)
			(stroke
				(width 0.1524)
				(type default)
			)
			(layer "B.SilkS")
		)
		(fp_line
			(start -0.7874 0.4064)
			(end 0.7874 0.4064)
			(stroke
				(width 0.1524)
				(type default)
			)
			(layer "B.SilkS")
		)
		(fp_line
			(start 0.7874 -0.4064)
			(end -0.7874 -0.4064)
			(stroke
				(width 0.1524)
				(type default)
			)
			(layer "B.SilkS")
		)
		(fp_line
			(start 0.7874 0.4064)
			(end 0.7874 -0.4064)
			(stroke
				(width 0.1524)
				(type default)
			)
			(layer "B.SilkS")
		)
		(fp_line
			(start -0.67945 -0.3048)
			(end -0.67945 0.3048)
			(stroke
				(width 0.1)
				(type default)
			)
			(layer "B.Fab")
		)
		(fp_line
			(start -0.67945 0.3048)
			(end -0.120396 0.3048)
			(stroke
				(width 0.1)
				(type default)
			)
			(layer "B.Fab")
		)
		(fp_line
			(start -0.12065 -0.3048)
			(end -0.67945 -0.3048)
			(stroke
				(width 0.1)
				(type default)
			)
			(layer "B.Fab")
		)
		(fp_line
			(start -0.12065 -0.2794)
			(end -0.12065 -0.3048)
			(stroke
				(width 0.1)
				(type default)
			)
			(layer "B.Fab")
		)
		(fp_line
			(start -0.120396 0.2794)
			(end 0.12065 0.2794)
			(stroke
				(width 0.1)
				(type default)
			)
			(layer "B.Fab")
		)
		(fp_line
			(start -0.120396 0.3048)
			(end -0.120396 0.2794)
			(stroke
				(width 0.1)
				(type default)
			)
			(layer "B.Fab")
		)
		(fp_line
			(start 0.12065 -0.305054)
			(end 0.12065 -0.2794)
			(stroke
				(width 0.1)
				(type default)
			)
			(layer "B.Fab")
		)
		(fp_line
			(start 0.12065 -0.2794)
			(end -0.12065 -0.2794)
			(stroke
				(width 0.1)
				(type default)
			)
			(layer "B.Fab")
		)
		(fp_line
			(start 0.12065 0.2794)
			(end 0.12065 0.3048)
			(stroke
				(width 0.1)
				(type default)
			)
			(layer "B.Fab")
		)
		(fp_line
			(start 0.12065 0.3048)
			(end 0.67945 0.3048)
			(stroke
				(width 0.1)
				(type default)
			)
			(layer "B.Fab")
		)
		(fp_line
			(start 0.67945 -0.305054)
			(end 0.12065 -0.305054)
			(stroke
				(width 0.1)
				(type default)
			)
			(layer "B.Fab")
		)
		(fp_line
			(start 0.67945 0.3048)
			(end 0.67945 -0.305054)
			(stroke
				(width 0.1)
				(type default)
			)
			(layer "B.Fab")
		)
		(pad "1" smd circle
			(at 0.40005 0 180)
			(size 0 0)
			(layers "B.Cu" "B.Mask" "B.Paste")
			(net "PVDDCR_SOC_P0")
		)
		(pad "2" smd circle
			(at -0.40005 0 180)
			(size 0 0)
			(layers "B.Cu" "B.Mask" "B.Paste")
			(net "GND")
		)
	)
	(footprint ""
		(layer "B.Cu")
		(at 121.452386 -264.354564)
		(property "Reference" "C2114"
			(at 0 0 0)
			(layer "B.SilkS")
			(hide yes)
			(effects
				(font
					(size 1.27 1.27)
				)
				(justify mirror)
			)
		)
		(property "Value" ""
			(at 0 0 0)
			(layer "B.Fab")
			(effects
				(font
					(size 1.27 1.27)
				)
				(justify mirror)
			)
		)
		(duplicate_pad_numbers_are_jumpers no)
		(fp_line
			(start -0.7874 -0.4064)
			(end -0.7874 0.4064)
			(stroke
				(width 0.1524)
				(type default)
			)
			(layer "B.SilkS")
		)
		(fp_line
			(start -0.7874 0.4064)
			(end 0.7874 0.4064)
			(stroke
				(width 0.1524)
				(type default)
			)
			(layer "B.SilkS")
		)
		(fp_line
			(start 0.7874 -0.4064)
			(end -0.7874 -0.4064)
			(stroke
				(width 0.1524)
				(type default)
			)
			(layer "B.SilkS")
		)
		(fp_line
			(start 0.7874 0.4064)
			(end 0.7874 -0.4064)
			(stroke
				(width 0.1524)
				(type default)
			)
			(layer "B.SilkS")
		)
		(fp_line
			(start -0.67945 -0.3048)
			(end -0.67945 0.3048)
			(stroke
				(width 0.1)
				(type default)
			)
			(layer "B.Fab")
		)
		(fp_line
			(start -0.67945 0.3048)
			(end -0.120396 0.3048)
			(stroke
				(width 0.1)
				(type default)
			)
			(layer "B.Fab")
		)
		(fp_line
			(start -0.12065 -0.3048)
			(end -0.67945 -0.3048)
			(stroke
				(width 0.1)
				(type default)
			)
			(layer "B.Fab")
		)
		(fp_line
			(start -0.12065 -0.2794)
			(end -0.12065 -0.3048)
			(stroke
				(width 0.1)
				(type default)
			)
			(layer "B.Fab")
		)
		(fp_line
			(start -0.120396 0.2794)
			(end 0.12065 0.2794)
			(stroke
				(width 0.1)
				(type default)
			)
			(layer "B.Fab")
		)
		(fp_line
			(start -0.120396 0.3048)
			(end -0.120396 0.2794)
			(stroke
				(width 0.1)
				(type default)
			)
			(layer "B.Fab")
		)
		(fp_line
			(start 0.12065 -0.305054)
			(end 0.12065 -0.2794)
			(stroke
				(width 0.1)
				(type default)
			)
			(layer "B.Fab")
		)
		(fp_line
			(start 0.12065 -0.2794)
			(end -0.12065 -0.2794)
			(stroke
				(width 0.1)
				(type default)
			)
			(layer "B.Fab")
		)
		(fp_line
			(start 0.12065 0.2794)
			(end 0.12065 0.3048)
			(stroke
				(width 0.1)
				(type default)
			)
			(layer "B.Fab")
		)
		(fp_line
			(start 0.12065 0.3048)
			(end 0.67945 0.3048)
			(stroke
				(width 0.1)
				(type default)
			)
			(layer "B.Fab")
		)
		(fp_line
			(start 0.67945 -0.305054)
			(end 0.12065 -0.305054)
			(stroke
				(width 0.1)
				(type default)
			)
			(layer "B.Fab")
		)
		(fp_line
			(start 0.67945 0.3048)
			(end 0.67945 -0.305054)
			(stroke
				(width 0.1)
				(type default)
			)
			(layer "B.Fab")
		)
		(pad "1" smd circle
			(at 0.40005 0 180)
			(size 0 0)
			(layers "B.Cu" "B.Mask" "B.Paste")
			(net "PVDD11_S3_P1")
		)
		(pad "2" smd circle
			(at -0.40005 0 180)
			(size 0 0)
			(layers "B.Cu" "B.Mask" "B.Paste")
			(net "GND")
		)
	)
	(footprint ""
		(layer "B.Cu")
		(at 371.297454 -264.35431)
		(property "Reference" "C2651"
			(at 0 0 0)
			(layer "B.SilkS")
			(hide yes)
			(effects
				(font
					(size 1.27 1.27)
				)
				(justify mirror)
			)
		)
		(property "Value" ""
			(at 0 0 0)
			(layer "B.Fab")
			(effects
				(font
					(size 1.27 1.27)
				)
				(justify mirror)
			)
		)
		(duplicate_pad_numbers_are_jumpers no)
		(fp_line
			(start -0.7874 -0.4064)
			(end -0.7874 0.4064)
			(stroke
				(width 0.1524)
				(type default)
			)
			(layer "B.SilkS")
		)
		(fp_line
			(start -0.7874 0.4064)
			(end 0.7874 0.4064)
			(stroke
				(width 0.1524)
				(type default)
			)
			(layer "B.SilkS")
		)
		(fp_line
			(start 0.7874 -0.4064)
			(end -0.7874 -0.4064)
			(stroke
				(width 0.1524)
				(type default)
			)
			(layer "B.SilkS")
		)
		(fp_line
			(start 0.7874 0.4064)
			(end 0.7874 -0.4064)
			(stroke
				(width 0.1524)
				(type default)
			)
			(layer "B.SilkS")
		)
		(fp_line
			(start -0.67945 -0.3048)
			(end -0.67945 0.3048)
			(stroke
				(width 0.1)
				(type default)
			)
			(layer "B.Fab")
		)
		(fp_line
			(start -0.67945 0.3048)
			(end -0.120396 0.3048)
			(stroke
				(width 0.1)
				(type default)
			)
			(layer "B.Fab")
		)
		(fp_line
			(start -0.12065 -0.3048)
			(end -0.67945 -0.3048)
			(stroke
				(width 0.1)
				(type default)
			)
			(layer "B.Fab")
		)
		(fp_line
			(start -0.12065 -0.2794)
			(end -0.12065 -0.3048)
			(stroke
				(width 0.1)
				(type default)
			)
			(layer "B.Fab")
		)
		(fp_line
			(start -0.120396 0.2794)
			(end 0.12065 0.2794)
			(stroke
				(width 0.1)
				(type default)
			)
			(layer "B.Fab")
		)
		(fp_line
			(start -0.120396 0.3048)
			(end -0.120396 0.2794)
			(stroke
				(width 0.1)
				(type default)
			)
			(layer "B.Fab")
		)
		(fp_line
			(start 0.12065 -0.305054)
			(end 0.12065 -0.2794)
			(stroke
				(width 0.1)
				(type default)
			)
			(layer "B.Fab")
		)
		(fp_line
			(start 0.12065 -0.2794)
			(end -0.12065 -0.2794)
			(stroke
				(width 0.1)
				(type default)
			)
			(layer "B.Fab")
		)
		(fp_line
			(start 0.12065 0.2794)
			(end 0.12065 0.3048)
			(stroke
				(width 0.1)
				(type default)
			)
			(layer "B.Fab")
		)
		(fp_line
			(start 0.12065 0.3048)
			(end 0.67945 0.3048)
			(stroke
				(width 0.1)
				(type default)
			)
			(layer "B.Fab")
		)
		(fp_line
			(start 0.67945 -0.305054)
			(end 0.12065 -0.305054)
			(stroke
				(width 0.1)
				(type default)
			)
			(layer "B.Fab")
		)
		(fp_line
			(start 0.67945 0.3048)
			(end 0.67945 -0.305054)
			(stroke
				(width 0.1)
				(type default)
			)
			(layer "B.Fab")
		)
		(pad "1" smd circle
			(at 0.40005 0 180)
			(size 0 0)
			(layers "B.Cu" "B.Mask" "B.Paste")
			(net "PVDD11_S3_P0")
		)
		(pad "2" smd circle
			(at -0.40005 0 180)
			(size 0 0)
			(layers "B.Cu" "B.Mask" "B.Paste")
			(net "GND")
		)
	)
	(footprint ""
		(layer "B.Cu")
		(at 295.724072 -192.660016 180)
		(property "Reference" "C145"
			(at 0 0 0)
			(layer "B.SilkS")
			(hide yes)
			(effects
				(font
					(size 1.27 1.27)
				)
				(justify mirror)
			)
		)
		(property "Value" ""
			(at 0 0 0)
			(layer "B.Fab")
			(effects
				(font
					(size 1.27 1.27)
				)
				(justify mirror)
			)
		)
		(duplicate_pad_numbers_are_jumpers no)
		(fp_line
			(start 1.524 0.762)
			(end 1.524 -0.762)
			(stroke
				(width 0.1524)
				(type default)
			)
			(layer "B.SilkS")
		)
		(fp_line
			(start 1.524 -0.762)
			(end -1.524 -0.762)
			(stroke
				(width 0.1524)
				(type default)
			)
			(layer "B.SilkS")
		)
		(fp_line
			(start -1.524 0.762)
			(end 1.524 0.762)
			(stroke
				(width 0.1524)
				(type default)
			)
			(layer "B.SilkS")
		)
		(fp_line
			(start -1.524 -0.762)
			(end -1.524 0.762)
			(stroke
				(width 0.1524)
				(type default)
			)
			(layer "B.SilkS")
		)
		(fp_line
			(start 1.1049 0.724916)
			(end -1.1049 0.724916)
			(stroke
				(width 0.1)
				(type default)
			)
			(layer "B.Fab")
		)
		(fp_line
			(start 1.1049 -0.724916)
			(end 1.1049 0.724916)
			(stroke
				(width 0.1)
				(type default)
			)
			(layer "B.Fab")
		)
		(fp_line
			(start -1.1049 0.724916)
			(end -1.1049 -0.724916)
			(stroke
				(width 0.1)
				(type default)
			)
			(layer "B.Fab")
		)
		(fp_line
			(start -1.1049 -0.724916)
			(end 1.1049 -0.724916)
			(stroke
				(width 0.1)
				(type default)
			)
			(layer "B.Fab")
		)
		(pad "1" smd rect
			(at 0.889 0 180)
			(size 1.016 1.27)
			(layers "B.Cu" "B.Mask" "B.Paste")
			(net "P12V_MEM_CPU0")
		)
		(pad "2" smd rect
			(at -0.889 0 180)
			(size 1.016 1.27)
			(layers "B.Cu" "B.Mask" "B.Paste")
			(net "GND")
		)
	)
)
